(kicad_pcb
	(version 20260206)
	(generator "pcbnew")
	(generator_version "10.0")
	(general
		(thickness 1.6)
		(legacy_teardrops no)
	)
	(paper "A4")
	(title_block
		(title "v1-chassis-manager — T6M_CM_d_v01_1031_1645.brd")
		(comment 1 "Open CloudServer (Microsoft) / footprints 2233-2242 of 2512")
	)
	(layers
		(0 "F.Cu" signal "TOP")
		(4 "In1.Cu" signal "GND1")
		(6 "In2.Cu" signal "IN1")
		(8 "In3.Cu" signal "VCC1")
		(10 "In4.Cu" signal "VCC2")
		(12 "In5.Cu" signal "GND2")
		(14 "In6.Cu" signal "IN2")
		(16 "In7.Cu" signal "IN3")
		(18 "In8.Cu" signal "GND3")
		(2 "B.Cu" signal "BOTTOM")
		(9 "F.Adhes" user "F.Adhesive")
		(11 "B.Adhes" user "B.Adhesive")
		(13 "F.Paste" user "Package Geometry/Pastemask Top")
		(15 "B.Paste" user "Package Geometry/Pastemask Bottom")
		(5 "F.SilkS" user "Ref Des/Silkscreen Top")
		(7 "B.SilkS" user "Ref Des/Silkscreen Bottom")
		(1 "F.Mask" user "Board Geometry/Soldermask Top")
		(3 "B.Mask" user "Board Geometry/Soldermask Bottom")
		(17 "Dwgs.User" user "User.Drawings")
		(19 "Cmts.User" user "User.Comments")
		(21 "Eco1.User" user "User.Eco1")
		(23 "Eco2.User" user "User.Eco2")
		(25 "Edge.Cuts" user "Board Geometry/Outline")
		(27 "Margin" user)
		(31 "F.CrtYd" user "Package Geometry/Place Bound Top")
		(29 "B.CrtYd" user "Package Geometry/Place Bound Bottom")
		(35 "F.Fab" user "Ref Des/Assembly Top")
		(33 "B.Fab" user "Ref Des/Assembly Bottom")
	)
	(footprint ""
		(layer "B.Cu")
		(at 51.691286 -123.025662 90)
		(property "Reference" "L19"
			(at -53.17871 -42.41165 270)
			(unlocked yes)
			(layer "B.SilkS")
			(effects
				(font
					(size 0.7874 0.5842)
					(thickness 0.1524)
				)
				(justify mirror)
			)
		)
		(property "Value" ""
			(at 0 0 90)
			(layer "B.Fab")
			(effects
				(font
					(size 1.27 1.27)
				)
				(justify mirror)
			)
		)
		(duplicate_pad_numbers_are_jumpers no)
		(fp_line
			(start 1.2954 -0.635)
			(end -1.2954 -0.635)
			(stroke
				(width 0.1524)
				(type default)
			)
			(layer "B.SilkS")
		)
		(fp_line
			(start 1.2954 -0.635)
			(end 1.2954 0.635)
			(stroke
				(width 0.1524)
				(type default)
			)
			(layer "B.SilkS")
		)
		(fp_line
			(start -1.2954 -0.635)
			(end -1.2954 0.635)
			(stroke
				(width 0.1524)
				(type default)
			)
			(layer "B.SilkS")
		)
		(fp_line
			(start 0.127 -0.5842)
			(end 0.127 0.5842)
			(stroke
				(width 0.1524)
				(type default)
			)
			(layer "B.SilkS")
		)
		(fp_line
			(start -0.127 -0.5842)
			(end -0.127 0.5842)
			(stroke
				(width 0.1524)
				(type default)
			)
			(layer "B.SilkS")
		)
		(fp_line
			(start -1.2954 0.635)
			(end 1.2954 0.635)
			(stroke
				(width 0.1524)
				(type default)
			)
			(layer "B.SilkS")
		)
		(fp_poly
			(pts
				(xy 0.9144 0.508) (xy 0.9144 0.3556) (xy 1.143 0.3556) (xy 1.143 -0.3556) (xy 0.9144 -0.3556) (xy 0.9144 -0.508)
				(xy -0.9144 -0.508) (xy -0.9144 -0.3556) (xy -1.143 -0.3556) (xy -1.143 0.3556) (xy -0.9144 0.3556)
				(xy -0.9144 0.508)
			)
			(stroke
				(width 0)
				(type default)
			)
			(fill no)
			(layer "B.CrtYd")
		)
		(pad "1" smd rect
			(at -0.7366 0 180)
			(size 0.7112 0.8128)
			(layers "B.Cu" "B.Mask" "B.Paste")
			(net "BMC_NODE1_V1PLLAV12")
		)
		(pad "2" smd rect
			(at 0.7366 0 180)
			(size 0.7112 0.8128)
			(layers "B.Cu" "B.Mask" "B.Paste")
			(net "P1V26_BMC_NODE1")
		)
	)
	(footprint ""
		(layer "B.Cu")
		(at 141.522196 -68.73113 -90)
		(property "Reference" "C351"
			(at 0.8382 -1.029462 270)
			(unlocked yes)
			(layer "B.SilkS")
			(effects
				(font
					(size 0.7874 0.5842)
					(thickness 0.1524)
				)
				(justify left mirror)
			)
		)
		(property "Value" ""
			(at 0 0 90)
			(layer "B.Fab")
			(effects
				(font
					(size 1.27 1.27)
				)
				(justify mirror)
			)
		)
		(duplicate_pad_numbers_are_jumpers no)
		(fp_line
			(start -0.7874 0.4064)
			(end 0.7874 0.4064)
			(stroke
				(width 0.1524)
				(type default)
			)
			(layer "B.SilkS")
		)
		(fp_line
			(start 0.7874 0.4064)
			(end 0.7874 -0.4064)
			(stroke
				(width 0.1524)
				(type default)
			)
			(layer "B.SilkS")
		)
		(fp_line
			(start 0 0.381)
			(end 0 -0.381)
			(stroke
				(width 0.1524)
				(type default)
			)
			(layer "B.SilkS")
		)
		(fp_line
			(start -0.7874 -0.4064)
			(end -0.7874 0.4064)
			(stroke
				(width 0.1524)
				(type default)
			)
			(layer "B.SilkS")
		)
		(fp_line
			(start 0.7874 -0.4064)
			(end -0.7874 -0.4064)
			(stroke
				(width 0.1524)
				(type default)
			)
			(layer "B.SilkS")
		)
		(fp_poly
			(pts
				(xy 0.5334 0.254) (xy 0.635 0.254) (xy 0.635 0.2286) (xy 0.635 -0.254) (xy 0.5334 -0.254) (xy 0.5334 -0.2794)
				(xy -0.5334 -0.2794) (xy -0.5334 -0.254) (xy -0.635 -0.254) (xy -0.635 0.254) (xy -0.5334 0.254)
				(xy -0.5334 0.2794) (xy 0.508 0.2794) (xy 0.5334 0.2794)
			)
			(stroke
				(width 0)
				(type default)
			)
			(fill no)
			(layer "B.CrtYd")
		)
		(pad "1" smd rect
			(at -0.40005 0 90)
			(size 0.4572 0.508)
			(layers "B.Cu" "B.Mask" "B.Paste")
			(net "P3V3_NODE1")
		)
		(pad "2" smd rect
			(at 0.40005 0 90)
			(size 0.4572 0.508)
			(layers "B.Cu" "B.Mask" "B.Paste")
			(net "GND")
		)
	)
	(footprint ""
		(layer "B.Cu")
		(at 139.227052 -151.28875 90)
		(property "Reference" "C868"
			(at 1.03378 3.437382 270)
			(unlocked yes)
			(layer "B.SilkS")
			(effects
				(font
					(size 0.7874 0.5842)
					(thickness 0.1524)
				)
				(justify left mirror)
			)
		)
		(property "Value" ""
			(at 0 0 90)
			(layer "B.Fab")
			(effects
				(font
					(size 1.27 1.27)
				)
				(justify mirror)
			)
		)
		(duplicate_pad_numbers_are_jumpers no)
		(fp_line
			(start 0.7874 -0.4064)
			(end -0.7874 -0.4064)
			(stroke
				(width 0.1524)
				(type default)
			)
			(layer "B.SilkS")
		)
		(fp_line
			(start -0.7874 -0.4064)
			(end -0.7874 0.4064)
			(stroke
				(width 0.1524)
				(type default)
			)
			(layer "B.SilkS")
		)
		(fp_line
			(start 0 0.381)
			(end 0 -0.381)
			(stroke
				(width 0.1524)
				(type default)
			)
			(layer "B.SilkS")
		)
		(fp_line
			(start 0.7874 0.4064)
			(end 0.7874 -0.4064)
			(stroke
				(width 0.1524)
				(type default)
			)
			(layer "B.SilkS")
		)
		(fp_line
			(start -0.7874 0.4064)
			(end 0.7874 0.4064)
			(stroke
				(width 0.1524)
				(type default)
			)
			(layer "B.SilkS")
		)
		(fp_poly
			(pts
				(xy 0.5334 0.254) (xy 0.635 0.254) (xy 0.635 0.2286) (xy 0.635 -0.254) (xy 0.5334 -0.254) (xy 0.5334 -0.2794)
				(xy -0.5334 -0.2794) (xy -0.5334 -0.254) (xy -0.635 -0.254) (xy -0.635 0.254) (xy -0.5334 0.254)
				(xy -0.5334 0.2794) (xy 0.508 0.2794) (xy 0.5334 0.2794)
			)
			(stroke
				(width 0)
				(type default)
			)
			(fill no)
			(layer "B.CrtYd")
		)
		(pad "1" smd rect
			(at -0.40005 0 270)
			(size 0.4572 0.508)
			(layers "B.Cu" "B.Mask" "B.Paste")
			(net "P3V3_NODE1")
		)
		(pad "2" smd rect
			(at 0.40005 0 270)
			(size 0.4572 0.508)
			(layers "B.Cu" "B.Mask" "B.Paste")
			(net "GND")
		)
	)
	(footprint ""
		(layer "B.Cu")
		(at 128.524 -59.436 -90)
		(property "Reference" "R1327"
			(at -1.143 0.02667 270)
			(unlocked yes)
			(layer "B.SilkS")
			(effects
				(font
					(size 0.7874 0.5842)
					(thickness 0.1524)
				)
				(justify left mirror)
			)
		)
		(property "Value" ""
			(at 0 0 90)
			(layer "B.Fab")
			(effects
				(font
					(size 1.27 1.27)
				)
				(justify mirror)
			)
		)
		(duplicate_pad_numbers_are_jumpers no)
		(fp_line
			(start -0.7874 0.4064)
			(end 0.7874 0.4064)
			(stroke
				(width 0.1524)
				(type default)
			)
			(layer "B.SilkS")
		)
		(fp_line
			(start 0.7874 0.4064)
			(end 0.7874 -0.4064)
			(stroke
				(width 0.1524)
				(type default)
			)
			(layer "B.SilkS")
		)
		(fp_line
			(start -0.7874 -0.4064)
			(end -0.7874 0.4064)
			(stroke
				(width 0.1524)
				(type default)
			)
			(layer "B.SilkS")
		)
		(fp_line
			(start 0.7874 -0.4064)
			(end -0.7874 -0.4064)
			(stroke
				(width 0.1524)
				(type default)
			)
			(layer "B.SilkS")
		)
		(fp_poly
			(pts
				(xy 0.508 0.2794) (xy 0.508 0.2286) (xy 0.635 0.2286) (xy 0.635 -0.254) (xy 0.5334 -0.254) (xy 0.5334 -0.2794)
				(xy -0.5334 -0.2794) (xy -0.5334 -0.254) (xy -0.635 -0.254) (xy -0.635 0.254) (xy -0.5334 0.254)
				(xy -0.5334 0.2794)
			)
			(stroke
				(width 0)
				(type default)
			)
			(fill no)
			(layer "B.CrtYd")
		)
		(pad "1" smd rect
			(at -0.40005 0 90)
			(size 0.4572 0.508)
			(layers "B.Cu" "B.Mask" "B.Paste")
			(net "UART_RI_P3_BUFFER_N")
		)
		(pad "2" smd rect
			(at 0.40005 0 90)
			(size 0.4572 0.508)
			(layers "B.Cu" "B.Mask" "B.Paste")
			(net "UART_RI_P3_N")
		)
	)
	(footprint ""
		(layer "B.Cu")
		(at 76.5683 -184.85358 90)
		(property "Reference" "R892"
			(at 4.15163 0.12065 270)
			(unlocked yes)
			(layer "B.SilkS")
			(effects
				(font
					(size 0.7874 0.5842)
					(thickness 0.1524)
				)
				(justify left mirror)
			)
		)
		(property "Value" ""
			(at 0 0 90)
			(layer "B.Fab")
			(effects
				(font
					(size 1.27 1.27)
				)
				(justify mirror)
			)
		)
		(duplicate_pad_numbers_are_jumpers no)
		(fp_line
			(start 0.7874 -0.4064)
			(end -0.7874 -0.4064)
			(stroke
				(width 0.1524)
				(type default)
			)
			(layer "B.SilkS")
		)
		(fp_line
			(start -0.7874 -0.4064)
			(end -0.7874 0.4064)
			(stroke
				(width 0.1524)
				(type default)
			)
			(layer "B.SilkS")
		)
		(fp_line
			(start 0.7874 0.4064)
			(end 0.7874 -0.4064)
			(stroke
				(width 0.1524)
				(type default)
			)
			(layer "B.SilkS")
		)
		(fp_line
			(start -0.7874 0.4064)
			(end 0.7874 0.4064)
			(stroke
				(width 0.1524)
				(type default)
			)
			(layer "B.SilkS")
		)
		(fp_poly
			(pts
				(xy 0.508 0.2794) (xy 0.508 0.2286) (xy 0.635 0.2286) (xy 0.635 -0.254) (xy 0.5334 -0.254) (xy 0.5334 -0.2794)
				(xy -0.5334 -0.2794) (xy -0.5334 -0.254) (xy -0.635 -0.254) (xy -0.635 0.254) (xy -0.5334 0.254)
				(xy -0.5334 0.2794)
			)
			(stroke
				(width 0)
				(type default)
			)
			(fill no)
			(layer "B.CrtYd")
		)
		(pad "1" smd rect
			(at -0.40005 0 270)
			(size 0.4572 0.508)
			(layers "B.Cu" "B.Mask" "B.Paste")
			(net "T3_NODE4_EN")
		)
		(pad "2" smd rect
			(at 0.40005 0 270)
			(size 0.4572 0.508)
			(layers "B.Cu" "B.Mask" "B.Paste")
			(net "T3_NODE4_EN_R")
		)
	)
	(footprint ""
		(layer "B.Cu")
		(at 165.210998 -156.39923 180)
		(property "Reference" "C471"
			(at 1.075182 -0.301498 0)
			(unlocked yes)
			(layer "B.SilkS")
			(effects
				(font
					(size 0.7874 0.5842)
					(thickness 0.1524)
				)
				(justify left mirror)
			)
		)
		(property "Value" ""
			(at 0 0 0)
			(layer "B.Fab")
			(effects
				(font
					(size 1.27 1.27)
				)
				(justify mirror)
			)
		)
		(duplicate_pad_numbers_are_jumpers no)
		(fp_line
			(start 0.7874 0.4064)
			(end 0.7874 -0.4064)
			(stroke
				(width 0.1524)
				(type default)
			)
			(layer "B.SilkS")
		)
		(fp_line
			(start 0.7874 -0.4064)
			(end -0.7874 -0.4064)
			(stroke
				(width 0.1524)
				(type default)
			)
			(layer "B.SilkS")
		)
		(fp_line
			(start 0 0.381)
			(end 0 -0.381)
			(stroke
				(width 0.1524)
				(type default)
			)
			(layer "B.SilkS")
		)
		(fp_line
			(start -0.7874 0.4064)
			(end 0.7874 0.4064)
			(stroke
				(width 0.1524)
				(type default)
			)
			(layer "B.SilkS")
		)
		(fp_line
			(start -0.7874 -0.4064)
			(end -0.7874 0.4064)
			(stroke
				(width 0.1524)
				(type default)
			)
			(layer "B.SilkS")
		)
		(fp_poly
			(pts
				(xy 0.5334 0.254) (xy 0.635 0.254) (xy 0.635 0.2286) (xy 0.635 -0.254) (xy 0.5334 -0.254) (xy 0.5334 -0.2794)
				(xy -0.5334 -0.2794) (xy -0.5334 -0.254) (xy -0.635 -0.254) (xy -0.635 0.254) (xy -0.5334 0.254)
				(xy -0.5334 0.2794) (xy 0.508 0.2794) (xy 0.5334 0.2794)
			)
			(stroke
				(width 0)
				(type default)
			)
			(fill no)
			(layer "B.CrtYd")
		)
		(pad "1" smd rect
			(at -0.40005 0)
			(size 0.4572 0.508)
			(layers "B.Cu" "B.Mask" "B.Paste")
			(net "P1V9_LAN2")
		)
		(pad "2" smd rect
			(at 0.40005 0)
			(size 0.4572 0.508)
			(layers "B.Cu" "B.Mask" "B.Paste")
			(net "GND")
		)
	)
	(footprint ""
		(layer "B.Cu")
		(at 131.988052 -151.28875 90)
		(property "Reference" "C875"
			(at 1.704086 0.21844 270)
			(unlocked yes)
			(layer "B.SilkS")
			(effects
				(font
					(size 0.7874 0.5842)
					(thickness 0.1524)
				)
				(justify left mirror)
			)
		)
		(property "Value" ""
			(at 0 0 90)
			(layer "B.Fab")
			(effects
				(font
					(size 1.27 1.27)
				)
				(justify mirror)
			)
		)
		(duplicate_pad_numbers_are_jumpers no)
		(fp_line
			(start 0.7874 -0.4064)
			(end -0.7874 -0.4064)
			(stroke
				(width 0.1524)
				(type default)
			)
			(layer "B.SilkS")
		)
		(fp_line
			(start -0.7874 -0.4064)
			(end -0.7874 0.4064)
			(stroke
				(width 0.1524)
				(type default)
			)
			(layer "B.SilkS")
		)
		(fp_line
			(start 0 0.381)
			(end 0 -0.381)
			(stroke
				(width 0.1524)
				(type default)
			)
			(layer "B.SilkS")
		)
		(fp_line
			(start 0.7874 0.4064)
			(end 0.7874 -0.4064)
			(stroke
				(width 0.1524)
				(type default)
			)
			(layer "B.SilkS")
		)
		(fp_line
			(start -0.7874 0.4064)
			(end 0.7874 0.4064)
			(stroke
				(width 0.1524)
				(type default)
			)
			(layer "B.SilkS")
		)
		(fp_poly
			(pts
				(xy 0.5334 0.254) (xy 0.635 0.254) (xy 0.635 0.2286) (xy 0.635 -0.254) (xy 0.5334 -0.254) (xy 0.5334 -0.2794)
				(xy -0.5334 -0.2794) (xy -0.5334 -0.254) (xy -0.635 -0.254) (xy -0.635 0.254) (xy -0.5334 0.254)
				(xy -0.5334 0.2794) (xy 0.508 0.2794) (xy 0.5334 0.2794)
			)
			(stroke
				(width 0)
				(type default)
			)
			(fill no)
			(layer "B.CrtYd")
		)
		(pad "1" smd rect
			(at -0.40005 0 270)
			(size 0.4572 0.508)
			(layers "B.Cu" "B.Mask" "B.Paste")
			(net "P1V0_NODE1")
		)
		(pad "2" smd rect
			(at 0.40005 0 270)
			(size 0.4572 0.508)
			(layers "B.Cu" "B.Mask" "B.Paste")
			(net "GND")
		)
	)
	(footprint ""
		(layer "B.Cu")
		(at 163.427918 -144.51203 -90)
		(property "Reference" "TP3"
			(at 0 0 90)
			(layer "B.SilkS")
			(hide yes)
			(effects
				(font
					(size 1.27 1.27)
				)
				(justify mirror)
			)
		)
		(property "Value" ""
			(at 0 0 90)
			(layer "B.Fab")
			(effects
				(font
					(size 1.27 1.27)
				)
				(justify mirror)
			)
		)
		(duplicate_pad_numbers_are_jumpers no)
		(fp_poly
			(pts
				(arc
					(start 0 -0.381)
					(mid 0 0.381)
					(end 0 -0.381)
				)
			)
			(stroke
				(width 0)
				(type default)
			)
			(fill no)
			(layer "B.CrtYd")
		)
		(pad "1" smd circle
			(at 0 0 90)
			(size 0.762 0.762)
			(layers "B.Cu" "B.Mask" "B.Paste")
			(net "N21357353")
		)
	)
	(footprint ""
		(layer "B.Cu")
		(at 56.171338 -80.166718 180)
		(property "Reference" "C48"
			(at 13.628878 -30.096968 0)
			(unlocked yes)
			(layer "B.SilkS")
			(effects
				(font
					(size 0.7874 0.5842)
					(thickness 0.1524)
				)
				(justify left mirror)
			)
		)
		(property "Value" ""
			(at 0 0 0)
			(layer "B.Fab")
			(effects
				(font
					(size 1.27 1.27)
				)
				(justify mirror)
			)
		)
		(duplicate_pad_numbers_are_jumpers no)
		(fp_line
			(start 0.7874 0.4064)
			(end 0.7874 -0.4064)
			(stroke
				(width 0.1524)
				(type default)
			)
			(layer "B.SilkS")
		)
		(fp_line
			(start 0.7874 -0.4064)
			(end -0.7874 -0.4064)
			(stroke
				(width 0.1524)
				(type default)
			)
			(layer "B.SilkS")
		)
		(fp_line
			(start 0 0.381)
			(end 0 -0.381)
			(stroke
				(width 0.1524)
				(type default)
			)
			(layer "B.SilkS")
		)
		(fp_line
			(start -0.7874 0.4064)
			(end 0.7874 0.4064)
			(stroke
				(width 0.1524)
				(type default)
			)
			(layer "B.SilkS")
		)
		(fp_line
			(start -0.7874 -0.4064)
			(end -0.7874 0.4064)
			(stroke
				(width 0.1524)
				(type default)
			)
			(layer "B.SilkS")
		)
		(fp_poly
			(pts
				(xy 0.5334 0.254) (xy 0.635 0.254) (xy 0.635 0.2286) (xy 0.635 -0.254) (xy 0.5334 -0.254) (xy 0.5334 -0.2794)
				(xy -0.5334 -0.2794) (xy -0.5334 -0.254) (xy -0.635 -0.254) (xy -0.635 0.254) (xy -0.5334 0.254)
				(xy -0.5334 0.2794) (xy 0.508 0.2794) (xy 0.5334 0.2794)
			)
			(stroke
				(width 0)
				(type default)
			)
			(fill no)
			(layer "B.CrtYd")
		)
		(pad "1" smd rect
			(at -0.40005 0)
			(size 0.4572 0.508)
			(layers "B.Cu" "B.Mask" "B.Paste")
			(net "P1V05_NODE1")
		)
		(pad "2" smd rect
			(at 0.40005 0)
			(size 0.4572 0.508)
			(layers "B.Cu" "B.Mask" "B.Paste")
			(net "GND")
		)
	)
	(footprint ""
		(layer "B.Cu")
		(at 94.234762 -184.815988 180)
		(property "Reference" "C665"
			(at -1.292098 5.936234 0)
			(unlocked yes)
			(layer "B.SilkS")
			(effects
				(font
					(size 0.7874 0.5842)
					(thickness 0.1524)
				)
				(justify left mirror)
			)
		)
		(property "Value" ""
			(at 0 0 0)
			(layer "B.Fab")
			(effects
				(font
					(size 1.27 1.27)
				)
				(justify mirror)
			)
		)
		(duplicate_pad_numbers_are_jumpers no)
		(fp_line
			(start 0.7874 0.4064)
			(end 0.7874 -0.4064)
			(stroke
				(width 0.1524)
				(type default)
			)
			(layer "B.SilkS")
		)
		(fp_line
			(start 0.7874 -0.4064)
			(end -0.7874 -0.4064)
			(stroke
				(width 0.1524)
				(type default)
			)
			(layer "B.SilkS")
		)
		(fp_line
			(start 0 0.381)
			(end 0 -0.381)
			(stroke
				(width 0.1524)
				(type default)
			)
			(layer "B.SilkS")
		)
		(fp_line
			(start -0.7874 0.4064)
			(end 0.7874 0.4064)
			(stroke
				(width 0.1524)
				(type default)
			)
			(layer "B.SilkS")
		)
		(fp_line
			(start -0.7874 -0.4064)
			(end -0.7874 0.4064)
			(stroke
				(width 0.1524)
				(type default)
			)
			(layer "B.SilkS")
		)
		(fp_poly
			(pts
				(xy 0.5334 0.254) (xy 0.635 0.254) (xy 0.635 0.2286) (xy 0.635 -0.254) (xy 0.5334 -0.254) (xy 0.5334 -0.2794)
				(xy -0.5334 -0.2794) (xy -0.5334 -0.254) (xy -0.635 -0.254) (xy -0.635 0.254) (xy -0.5334 0.254)
				(xy -0.5334 0.2794) (xy 0.508 0.2794) (xy 0.5334 0.2794)
			)
			(stroke
				(width 0)
				(type default)
			)
			(fill no)
			(layer "B.CrtYd")
		)
		(pad "1" smd rect
			(at -0.40005 0)
			(size 0.4572 0.508)
			(layers "B.Cu" "B.Mask" "B.Paste")
			(net "T5_NODE3_EN_R")
		)
		(pad "2" smd rect
			(at 0.40005 0)
			(size 0.4572 0.508)
			(layers "B.Cu" "B.Mask" "B.Paste")
			(net "GND")
		)
	)
)
